# T6G (Grand Teton) — schematic netlist excerpt (pin names and nets, part order shuffled) for the footprints in the layout excerpt that follows; sources: Cadence DE-HDL packaged netlist, KiCad conversion of 04192023_DAF0TMB3IC0_F0TG_MB_C_brd_V02_OCP.brd

C2325  Q_CAP  22UF 4V 20% X6S  pkg C0402  page 73 : A = PVDDCR_CPU0_P1 ; B = GND
R511  Q_RES  15 1% CHIP  pkg 0402LF  page 48 : A = M_L_CPU1_ALERT_N ; B = M_L_CPU1_ALERT_R_N

(kicad_pcb
	(version 20260206)
	(generator "pcbnew")
	(generator_version "10.0")
	(general
		(thickness 1.6)
		(legacy_teardrops no)
	)
	(paper "A4")
	(title_block
		(title "04192023_DAF0TMB3IC0_F0TG_MB_C_brd_V02_OCP.brd")
		(comment 1 "Grand Teton / footprints 5972-5973 of 8354")
	)
	(layers
		(0 "F.Cu" signal "TOP")
		(4 "In1.Cu" signal "GND")
		(6 "In2.Cu" signal "IN1")
		(8 "In3.Cu" signal "GND1")
		(10 "In4.Cu" signal "IN2")
		(12 "In5.Cu" signal "GND2")
		(14 "In6.Cu" signal "IN3")
		(16 "In7.Cu" signal "GND3")
		(18 "In8.Cu" signal "VCC")
		(20 "In9.Cu" signal "VCC1")
		(22 "In10.Cu" signal "GND4")
		(24 "In11.Cu" signal "IN4")
		(26 "In12.Cu" signal "GND5")
		(28 "In13.Cu" signal "IN5")
		(30 "In14.Cu" signal "GND6")
		(32 "In15.Cu" signal "IN6")
		(34 "In16.Cu" signal "GND7")
		(2 "B.Cu" signal "BOTTOM")
		(9 "F.Adhes" user "F.Adhesive")
		(11 "B.Adhes" user "B.Adhesive")
		(13 "F.Paste" user "Package Geometry/Pastemask Top")
		(15 "B.Paste" user "Package Geometry/Pastemask Bottom")
		(5 "F.SilkS" user "Ref Des/Silkscreen Top")
		(7 "B.SilkS" user "Ref Des/Silkscreen Bottom")
		(1 "F.Mask" user "Board Geometry/Soldermask Top")
		(3 "B.Mask" user "Board Geometry/Soldermask Bottom")
		(17 "Dwgs.User" user "User.Drawings")
		(19 "Cmts.User" user "User.Comments")
		(21 "Eco1.User" user "User.Eco1")
		(23 "Eco2.User" user "User.Eco2")
		(25 "Edge.Cuts" user "Board Geometry/Outline")
		(27 "Margin" user)
		(31 "F.CrtYd" user "Package Geometry/Place Bound Top")
		(29 "B.CrtYd" user "Package Geometry/Place Bound Bottom")
		(35 "F.Fab" user "Ref Des/Assembly Top")
		(33 "B.Fab" user "Ref Des/Assembly Bottom")
	)
	(footprint ""
		(layer "B.Cu")
		(at 205.25105 -244.085364)
		(property "Reference" "R511"
			(at 0 0 0)
			(layer "B.SilkS")
			(hide yes)
			(effects
				(font
					(size 1.27 1.27)
				)
				(justify mirror)
			)
		)
		(property "Value" ""
			(at 0 0 0)
			(layer "B.Fab")
			(effects
				(font
					(size 1.27 1.27)
				)
				(justify mirror)
			)
		)
		(duplicate_pad_numbers_are_jumpers no)
		(fp_line
			(start -0.7874 -0.4064)
			(end -0.7874 0.4064)
			(stroke
				(width 0.1524)
				(type default)
			)
			(layer "B.SilkS")
		)
		(fp_line
			(start -0.7874 0.4064)
			(end 0.7874 0.4064)
			(stroke
				(width 0.1524)
				(type default)
			)
			(layer "B.SilkS")
		)
		(fp_line
			(start 0.7874 -0.4064)
			(end -0.7874 -0.4064)
			(stroke
				(width 0.1524)
				(type default)
			)
			(layer "B.SilkS")
		)
		(fp_line
			(start 0.7874 0.4064)
			(end 0.7874 -0.4064)
			(stroke
				(width 0.1524)
				(type default)
			)
			(layer "B.SilkS")
		)
		(fp_line
			(start -0.67945 -0.3048)
			(end -0.67945 0.3048)
			(stroke
				(width 0.1)
				(type default)
			)
			(layer "B.Fab")
		)
		(fp_line
			(start -0.67945 0.3048)
			(end -0.120396 0.3048)
			(stroke
				(width 0.1)
				(type default)
			)
			(layer "B.Fab")
		)
		(fp_line
			(start -0.12065 -0.3048)
			(end -0.67945 -0.3048)
			(stroke
				(width 0.1)
				(type default)
			)
			(layer "B.Fab")
		)
		(fp_line
			(start -0.12065 -0.2794)
			(end -0.12065 -0.3048)
			(stroke
				(width 0.1)
				(type default)
			)
			(layer "B.Fab")
		)
		(fp_line
			(start -0.120396 0.2794)
			(end 0.12065 0.2794)
			(stroke
				(width 0.1)
				(type default)
			)
			(layer "B.Fab")
		)
		(fp_line
			(start -0.120396 0.3048)
			(end -0.120396 0.2794)
			(stroke
				(width 0.1)
				(type default)
			)
			(layer "B.Fab")
		)
		(fp_line
			(start 0.12065 -0.305054)
			(end 0.12065 -0.2794)
			(stroke
				(width 0.1)
				(type default)
			)
			(layer "B.Fab")
		)
		(fp_line
			(start 0.12065 -0.2794)
			(end -0.12065 -0.2794)
			(stroke
				(width 0.1)
				(type default)
			)
			(layer "B.Fab")
		)
		(fp_line
			(start 0.12065 0.2794)
			(end 0.12065 0.3048)
			(stroke
				(width 0.1)
				(type default)
			)
			(layer "B.Fab")
		)
		(fp_line
			(start 0.12065 0.3048)
			(end 0.67945 0.3048)
			(stroke
				(width 0.1)
				(type default)
			)
			(layer "B.Fab")
		)
		(fp_line
			(start 0.67945 -0.305054)
			(end 0.12065 -0.305054)
			(stroke
				(width 0.1)
				(type default)
			)
			(layer "B.Fab")
		)
		(fp_line
			(start 0.67945 0.3048)
			(end 0.67945 -0.305054)
			(stroke
				(width 0.1)
				(type default)
			)
			(layer "B.Fab")
		)
		(pad "1" smd circle
			(at 0.40005 0 180)
			(size 0 0)
			(layers "B.Cu" "B.Mask" "B.Paste")
			(net "M_L_CPU1_ALERT_N")
		)
		(pad "2" smd circle
			(at -0.40005 0 180)
			(size 0 0)
			(layers "B.Cu" "B.Mask" "B.Paste")
			(net "M_L_CPU1_ALERT_R_N")
		)
	)
	(footprint ""
		(layer "B.Cu")
		(at 121.706386 -249.368564)
		(property "Reference" "C2325"
			(at 0 0 0)
			(layer "B.SilkS")
			(hide yes)
			(effects
				(font
					(size 1.27 1.27)
				)
				(justify mirror)
			)
		)
		(property "Value" ""
			(at 0 0 0)
			(layer "B.Fab")
			(effects
				(font
					(size 1.27 1.27)
				)
				(justify mirror)
			)
		)
		(duplicate_pad_numbers_are_jumpers no)
		(fp_line
			(start -0.7874 -0.4064)
			(end -0.7874 0.4064)
			(stroke
				(width 0.1524)
				(type default)
			)
			(layer "B.SilkS")
		)
		(fp_line
			(start -0.7874 0.4064)
			(end 0.7874 0.4064)
			(stroke
				(width 0.1524)
				(type default)
			)
			(layer "B.SilkS")
		)
		(fp_line
			(start 0.7874 -0.4064)
			(end -0.7874 -0.4064)
			(stroke
				(width 0.1524)
				(type default)
			)
			(layer "B.SilkS")
		)
		(fp_line
			(start 0.7874 0.4064)
			(end 0.7874 -0.4064)
			(stroke
				(width 0.1524)
				(type default)
			)
			(layer "B.SilkS")
		)
		(fp_line
			(start -0.67945 -0.3048)
			(end -0.67945 0.3048)
			(stroke
				(width 0.1)
				(type default)
			)
			(layer "B.Fab")
		)
		(fp_line
			(start -0.67945 0.3048)
			(end -0.120396 0.3048)
			(stroke
				(width 0.1)
				(type default)
			)
			(layer "B.Fab")
		)
		(fp_line
			(start -0.12065 -0.3048)
			(end -0.67945 -0.3048)
			(stroke
				(width 0.1)
				(type default)
			)
			(layer "B.Fab")
		)
		(fp_line
			(start -0.12065 -0.2794)
			(end -0.12065 -0.3048)
			(stroke
				(width 0.1)
				(type default)
			)
			(layer "B.Fab")
		)
		(fp_line
			(start -0.120396 0.2794)
			(end 0.12065 0.2794)
			(stroke
				(width 0.1)
				(type default)
			)
			(layer "B.Fab")
		)
		(fp_line
			(start -0.120396 0.3048)
			(end -0.120396 0.2794)
			(stroke
				(width 0.1)
				(type default)
			)
			(layer "B.Fab")
		)
		(fp_line
			(start 0.12065 -0.305054)
			(end 0.12065 -0.2794)
			(stroke
				(width 0.1)
				(type default)
			)
			(layer "B.Fab")
		)
		(fp_line
			(start 0.12065 -0.2794)
			(end -0.12065 -0.2794)
			(stroke
				(width 0.1)
				(type default)
			)
			(layer "B.Fab")
		)
		(fp_line
			(start 0.12065 0.2794)
			(end 0.12065 0.3048)
			(stroke
				(width 0.1)
				(type default)
			)
			(layer "B.Fab")
		)
		(fp_line
			(start 0.12065 0.3048)
			(end 0.67945 0.3048)
			(stroke
				(width 0.1)
				(type default)
			)
			(layer "B.Fab")
		)
		(fp_line
			(start 0.67945 -0.305054)
			(end 0.12065 -0.305054)
			(stroke
				(width 0.1)
				(type default)
			)
			(layer "B.Fab")
		)
		(fp_line
			(start 0.67945 0.3048)
			(end 0.67945 -0.305054)
			(stroke
				(width 0.1)
				(type default)
			)
			(layer "B.Fab")
		)
		(pad "1" smd circle
			(at 0.40005 0 180)
			(size 0 0)
			(layers "B.Cu" "B.Mask" "B.Paste")
			(net "PVDDCR_CPU0_P1")
		)
		(pad "2" smd circle
			(at -0.40005 0 180)
			(size 0 0)
			(layers "B.Cu" "B.Mask" "B.Paste")
			(net "GND")
		)
	)
)
